(kicad_pcb
	(version 20260206)
	(generator "pcbnew")
	(generator_version "10.0")
	(general
		(thickness 1.6)
		(legacy_teardrops no)
	)
	(paper "A4")
	(title_block
		(title "03242023_DA0F0TMBIJ0_F0T_Motherboard_J_brd_V01_OCP.brd")
		(comment 1 "Grand Teton / footprints 3754-3759 of 6105")
	)
	(layers
		(0 "F.Cu" signal "TOP")
		(4 "In1.Cu" signal "GND")
		(6 "In2.Cu" signal "IN1")
		(8 "In3.Cu" signal "GND1")
		(10 "In4.Cu" signal "IN2")
		(12 "In5.Cu" signal "GND2")
		(14 "In6.Cu" signal "IN3")
		(16 "In7.Cu" signal "GND3")
		(18 "In8.Cu" signal "VCC")
		(20 "In9.Cu" signal "VCC1")
		(22 "In10.Cu" signal "GND4")
		(24 "In11.Cu" signal "IN4")
		(26 "In12.Cu" signal "GND5")
		(28 "In13.Cu" signal "IN5")
		(30 "In14.Cu" signal "GND6")
		(32 "In15.Cu" signal "IN6")
		(34 "In16.Cu" signal "GND7")
		(2 "B.Cu" signal "BOTTOM")
		(9 "F.Adhes" user "F.Adhesive")
		(11 "B.Adhes" user "B.Adhesive")
		(13 "F.Paste" user "Package Geometry/Pastemask Top")
		(15 "B.Paste" user "Package Geometry/Pastemask Bottom")
		(5 "F.SilkS" user "Ref Des/Silkscreen Top")
		(7 "B.SilkS" user "Ref Des/Silkscreen Bottom")
		(1 "F.Mask" user "Board Geometry/Soldermask Top")
		(3 "B.Mask" user "Board Geometry/Soldermask Bottom")
		(17 "Dwgs.User" user "User.Drawings")
		(19 "Cmts.User" user "User.Comments")
		(21 "Eco1.User" user "User.Eco1")
		(23 "Eco2.User" user "User.Eco2")
		(25 "Edge.Cuts" user "Board Geometry/Outline")
		(27 "Margin" user)
		(31 "F.CrtYd" user "Package Geometry/Place Bound Top")
		(29 "B.CrtYd" user "Package Geometry/Place Bound Bottom")
		(35 "F.Fab" user "Ref Des/Assembly Top")
		(33 "B.Fab" user "Ref Des/Assembly Bottom")
	)
	(footprint ""
		(layer "F.Cu")
		(at 73.506076 -174.008034 180)
		(property "Reference" "PR569"
			(at 0 0 180)
			(layer "F.SilkS")
			(hide yes)
			(effects
				(font
					(size 1.27 1.27)
				)
			)
		)
		(property "Value" ""
			(at 0 0 180)
			(layer "F.Fab")
			(effects
				(font
					(size 1.27 1.27)
				)
			)
		)
		(duplicate_pad_numbers_are_jumpers no)
		(fp_line
			(start 0.7874 0.4064)
			(end -0.7874 0.4064)
			(stroke
				(width 0.1524)
				(type default)
			)
			(layer "F.SilkS")
		)
		(fp_line
			(start 0.7874 -0.4064)
			(end 0.7874 0.4064)
			(stroke
				(width 0.1524)
				(type default)
			)
			(layer "F.SilkS")
		)
		(fp_line
			(start -0.7874 0.4064)
			(end -0.7874 -0.4064)
			(stroke
				(width 0.1524)
				(type default)
			)
			(layer "F.SilkS")
		)
		(fp_line
			(start -0.7874 -0.4064)
			(end 0.7874 -0.4064)
			(stroke
				(width 0.1524)
				(type default)
			)
			(layer "F.SilkS")
		)
		(fp_line
			(start 0.67945 0.3048)
			(end 0.120396 0.3048)
			(stroke
				(width 0.1)
				(type default)
			)
			(layer "F.Fab")
		)
		(fp_line
			(start 0.67945 -0.3048)
			(end 0.67945 0.3048)
			(stroke
				(width 0.1)
				(type default)
			)
			(layer "F.Fab")
		)
		(fp_line
			(start 0.12065 -0.2794)
			(end 0.12065 -0.3048)
			(stroke
				(width 0.1)
				(type default)
			)
			(layer "F.Fab")
		)
		(fp_line
			(start 0.12065 -0.3048)
			(end 0.67945 -0.3048)
			(stroke
				(width 0.1)
				(type default)
			)
			(layer "F.Fab")
		)
		(fp_line
			(start 0.120396 0.3048)
			(end 0.120396 0.2794)
			(stroke
				(width 0.1)
				(type default)
			)
			(layer "F.Fab")
		)
		(fp_line
			(start 0.120396 0.2794)
			(end -0.12065 0.2794)
			(stroke
				(width 0.1)
				(type default)
			)
			(layer "F.Fab")
		)
		(fp_line
			(start -0.12065 0.3048)
			(end -0.67945 0.3048)
			(stroke
				(width 0.1)
				(type default)
			)
			(layer "F.Fab")
		)
		(fp_line
			(start -0.12065 0.2794)
			(end -0.12065 0.3048)
			(stroke
				(width 0.1)
				(type default)
			)
			(layer "F.Fab")
		)
		(fp_line
			(start -0.12065 -0.2794)
			(end 0.12065 -0.2794)
			(stroke
				(width 0.1)
				(type default)
			)
			(layer "F.Fab")
		)
		(fp_line
			(start -0.12065 -0.305054)
			(end -0.12065 -0.2794)
			(stroke
				(width 0.1)
				(type default)
			)
			(layer "F.Fab")
		)
		(fp_line
			(start -0.67945 0.3048)
			(end -0.67945 -0.305054)
			(stroke
				(width 0.1)
				(type default)
			)
			(layer "F.Fab")
		)
		(fp_line
			(start -0.67945 -0.305054)
			(end -0.12065 -0.305054)
			(stroke
				(width 0.1)
				(type default)
			)
			(layer "F.Fab")
		)
		(pad "1" smd circle
			(at -0.40005 0 180)
			(size 0 0)
			(layers "F.Cu" "F.Mask" "F.Paste")
			(net "VSENSE_PVCCFA_EHV_CPU1_DP")
		)
		(pad "2" smd circle
			(at 0.40005 0 180)
			(size 0 0)
			(layers "F.Cu" "F.Mask" "F.Paste")
			(net "PVCCFA_EHV_CPU1")
		)
	)
	(footprint ""
		(layer "F.Cu")
		(at 20.190714 -106.761026)
		(property "Reference" "R3667"
			(at 0 0 0)
			(layer "F.SilkS")
			(hide yes)
			(effects
				(font
					(size 1.27 1.27)
				)
			)
		)
		(property "Value" ""
			(at 0 0 0)
			(layer "F.Fab")
			(effects
				(font
					(size 1.27 1.27)
				)
			)
		)
		(duplicate_pad_numbers_are_jumpers no)
		(fp_line
			(start -0.7874 -0.4064)
			(end 0.7874 -0.4064)
			(stroke
				(width 0.1524)
				(type default)
			)
			(layer "F.SilkS")
		)
		(fp_line
			(start -0.7874 0.4064)
			(end -0.7874 -0.4064)
			(stroke
				(width 0.1524)
				(type default)
			)
			(layer "F.SilkS")
		)
		(fp_line
			(start 0.7874 -0.4064)
			(end 0.7874 0.4064)
			(stroke
				(width 0.1524)
				(type default)
			)
			(layer "F.SilkS")
		)
		(fp_line
			(start 0.7874 0.4064)
			(end -0.7874 0.4064)
			(stroke
				(width 0.1524)
				(type default)
			)
			(layer "F.SilkS")
		)
		(fp_line
			(start -0.67945 -0.305054)
			(end -0.12065 -0.305054)
			(stroke
				(width 0.1)
				(type default)
			)
			(layer "F.Fab")
		)
		(fp_line
			(start -0.67945 0.3048)
			(end -0.67945 -0.305054)
			(stroke
				(width 0.1)
				(type default)
			)
			(layer "F.Fab")
		)
		(fp_line
			(start -0.12065 -0.305054)
			(end -0.12065 -0.2794)
			(stroke
				(width 0.1)
				(type default)
			)
			(layer "F.Fab")
		)
		(fp_line
			(start -0.12065 -0.2794)
			(end 0.12065 -0.2794)
			(stroke
				(width 0.1)
				(type default)
			)
			(layer "F.Fab")
		)
		(fp_line
			(start -0.12065 0.2794)
			(end -0.12065 0.3048)
			(stroke
				(width 0.1)
				(type default)
			)
			(layer "F.Fab")
		)
		(fp_line
			(start -0.12065 0.3048)
			(end -0.67945 0.3048)
			(stroke
				(width 0.1)
				(type default)
			)
			(layer "F.Fab")
		)
		(fp_line
			(start 0.120396 0.2794)
			(end -0.12065 0.2794)
			(stroke
				(width 0.1)
				(type default)
			)
			(layer "F.Fab")
		)
		(fp_line
			(start 0.120396 0.3048)
			(end 0.120396 0.2794)
			(stroke
				(width 0.1)
				(type default)
			)
			(layer "F.Fab")
		)
		(fp_line
			(start 0.12065 -0.3048)
			(end 0.67945 -0.3048)
			(stroke
				(width 0.1)
				(type default)
			)
			(layer "F.Fab")
		)
		(fp_line
			(start 0.12065 -0.2794)
			(end 0.12065 -0.3048)
			(stroke
				(width 0.1)
				(type default)
			)
			(layer "F.Fab")
		)
		(fp_line
			(start 0.67945 -0.3048)
			(end 0.67945 0.3048)
			(stroke
				(width 0.1)
				(type default)
			)
			(layer "F.Fab")
		)
		(fp_line
			(start 0.67945 0.3048)
			(end 0.120396 0.3048)
			(stroke
				(width 0.1)
				(type default)
			)
			(layer "F.Fab")
		)
		(pad "1" smd circle
			(at -0.40005 0)
			(size 0 0)
			(layers "F.Cu" "F.Mask" "F.Paste")
			(net "P3V3_AUX")
		)
		(pad "2" smd circle
			(at 0.40005 0)
			(size 0 0)
			(layers "F.Cu" "F.Mask" "F.Paste")
			(net "ADC128_A1")
		)
	)
	(footprint ""
		(layer "F.Cu")
		(at 364.978442 -393.33805)
		(property "Reference" "Q136"
			(at -1.4224 -1.768348 0)
			(unlocked yes)
			(layer "F.SilkS")
			(effects
				(font
					(size 0.7874 0.5842)
					(thickness 0.1524)
				)
				(justify left)
			)
		)
		(property "Value" ""
			(at 0 0 0)
			(layer "F.Fab")
			(effects
				(font
					(size 1.27 1.27)
				)
			)
		)
		(duplicate_pad_numbers_are_jumpers no)
		(fp_line
			(start -1.332738 -1.100074)
			(end -0.4826 -1.100074)
			(stroke
				(width 0.1524)
				(type default)
			)
			(layer "F.SilkS")
		)
		(fp_line
			(start -1.332738 1.100074)
			(end -1.332738 -1.100074)
			(stroke
				(width 0.1524)
				(type default)
			)
			(layer "F.SilkS")
		)
		(fp_line
			(start -0.4826 -1.100074)
			(end 0 -0.541274)
			(stroke
				(width 0.1524)
				(type default)
			)
			(layer "F.SilkS")
		)
		(fp_line
			(start 0 -0.541274)
			(end 0.4826 -1.100074)
			(stroke
				(width 0.1524)
				(type default)
			)
			(layer "F.SilkS")
		)
		(fp_line
			(start 0.4826 -1.100074)
			(end 1.332738 -1.100074)
			(stroke
				(width 0.1524)
				(type default)
			)
			(layer "F.SilkS")
		)
		(fp_line
			(start 1.332738 -1.100074)
			(end 1.332738 1.100074)
			(stroke
				(width 0.1524)
				(type default)
			)
			(layer "F.SilkS")
		)
		(fp_line
			(start 1.332738 1.100074)
			(end -1.332738 1.100074)
			(stroke
				(width 0.1524)
				(type default)
			)
			(layer "F.SilkS")
		)
		(fp_poly
			(pts
				(xy -2.2352 -1.001014) (xy -1.533144 -0.649986) (xy -2.2352 -0.298958)
			)
			(stroke
				(width 0)
				(type default)
			)
			(fill yes)
			(layer "F.SilkS")
		)
		(fp_line
			(start -0.674878 -1.100074)
			(end 0.674878 -1.100074)
			(stroke
				(width 0.1)
				(type default)
			)
			(layer "F.Fab")
		)
		(fp_line
			(start -0.674878 1.100074)
			(end -0.674878 -1.100074)
			(stroke
				(width 0.1)
				(type default)
			)
			(layer "F.Fab")
		)
		(fp_line
			(start 0.674878 -1.100074)
			(end 0.674878 1.100074)
			(stroke
				(width 0.1)
				(type default)
			)
			(layer "F.Fab")
		)
		(fp_line
			(start 0.674878 1.100074)
			(end -0.674878 1.100074)
			(stroke
				(width 0.1)
				(type default)
			)
			(layer "F.Fab")
		)
		(fp_poly
			(pts
				(xy -2.2352 -0.298958) (xy -2.2352 -1.001014) (xy -1.533144 -0.649986)
			)
			(stroke
				(width 0)
				(type default)
			)
			(fill yes)
			(layer "F.Fab")
		)
		(pad "1" smd rect
			(at -0.94996 -0.649986 90)
			(size 0.4318 0.508)
			(layers "F.Cu" "F.Mask" "F.Paste")
			(net "GND")
		)
		(pad "2" smd rect
			(at -0.94996 0 90)
			(size 0.4318 0.508)
			(layers "F.Cu" "F.Mask" "F.Paste")
			(net "GPU_3V3IO_RSVD4")
		)
		(pad "3" smd rect
			(at -0.94996 0.649986 90)
			(size 0.4318 0.508)
			(layers "F.Cu" "F.Mask" "F.Paste")
			(net "GPU_3V3IO_RSVD4_ISO")
		)
		(pad "4" smd rect
			(at 0.94996 0.649986 90)
			(size 0.4318 0.508)
			(layers "F.Cu" "F.Mask" "F.Paste")
			(net "GND")
		)
		(pad "5" smd rect
			(at 0.94996 0 90)
			(size 0.4318 0.508)
			(layers "F.Cu" "F.Mask" "F.Paste")
			(net "GPU_3V3IO_RSVD4_N")
		)
		(pad "6" smd rect
			(at 0.94996 -0.649986 90)
			(size 0.4318 0.508)
			(layers "F.Cu" "F.Mask" "F.Paste")
			(net "GPU_3V3IO_RSVD4_N")
		)
	)
	(footprint ""
		(layer "F.Cu")
		(at 21.7932 -410.7942 90)
		(property "Reference" "R4735"
			(at 0 0 90)
			(layer "F.SilkS")
			(hide yes)
			(effects
				(font
					(size 1.27 1.27)
				)
			)
		)
		(property "Value" ""
			(at 0 0 90)
			(layer "F.Fab")
			(effects
				(font
					(size 1.27 1.27)
				)
			)
		)
		(duplicate_pad_numbers_are_jumpers no)
		(fp_line
			(start 0.7874 -0.4064)
			(end 0.7874 0.4064)
			(stroke
				(width 0.1524)
				(type default)
			)
			(layer "F.SilkS")
		)
		(fp_line
			(start -0.7874 -0.4064)
			(end 0.7874 -0.4064)
			(stroke
				(width 0.1524)
				(type default)
			)
			(layer "F.SilkS")
		)
		(fp_line
			(start 0.7874 0.4064)
			(end -0.7874 0.4064)
			(stroke
				(width 0.1524)
				(type default)
			)
			(layer "F.SilkS")
		)
		(fp_line
			(start -0.7874 0.4064)
			(end -0.7874 -0.4064)
			(stroke
				(width 0.1524)
				(type default)
			)
			(layer "F.SilkS")
		)
		(fp_line
			(start -0.12065 -0.305054)
			(end -0.12065 -0.2794)
			(stroke
				(width 0.1)
				(type default)
			)
			(layer "F.Fab")
		)
		(fp_line
			(start -0.67945 -0.305054)
			(end -0.12065 -0.305054)
			(stroke
				(width 0.1)
				(type default)
			)
			(layer "F.Fab")
		)
		(fp_line
			(start 0.67945 -0.3048)
			(end 0.67945 0.3048)
			(stroke
				(width 0.1)
				(type default)
			)
			(layer "F.Fab")
		)
		(fp_line
			(start 0.12065 -0.3048)
			(end 0.67945 -0.3048)
			(stroke
				(width 0.1)
				(type default)
			)
			(layer "F.Fab")
		)
		(fp_line
			(start 0.12065 -0.2794)
			(end 0.12065 -0.3048)
			(stroke
				(width 0.1)
				(type default)
			)
			(layer "F.Fab")
		)
		(fp_line
			(start -0.12065 -0.2794)
			(end 0.12065 -0.2794)
			(stroke
				(width 0.1)
				(type default)
			)
			(layer "F.Fab")
		)
		(fp_line
			(start 0.120396 0.2794)
			(end -0.12065 0.2794)
			(stroke
				(width 0.1)
				(type default)
			)
			(layer "F.Fab")
		)
		(fp_line
			(start -0.12065 0.2794)
			(end -0.12065 0.3048)
			(stroke
				(width 0.1)
				(type default)
			)
			(layer "F.Fab")
		)
		(fp_line
			(start 0.67945 0.3048)
			(end 0.120396 0.3048)
			(stroke
				(width 0.1)
				(type default)
			)
			(layer "F.Fab")
		)
		(fp_line
			(start 0.120396 0.3048)
			(end 0.120396 0.2794)
			(stroke
				(width 0.1)
				(type default)
			)
			(layer "F.Fab")
		)
		(fp_line
			(start -0.12065 0.3048)
			(end -0.67945 0.3048)
			(stroke
				(width 0.1)
				(type default)
			)
			(layer "F.Fab")
		)
		(fp_line
			(start -0.67945 0.3048)
			(end -0.67945 -0.305054)
			(stroke
				(width 0.1)
				(type default)
			)
			(layer "F.Fab")
		)
		(pad "1" smd circle
			(at -0.40005 0 90)
			(size 0 0)
			(layers "F.Cu" "F.Mask" "F.Paste")
			(net "PRSNT_CABLE_SWB_B2_ISO_N")
		)
		(pad "2" smd circle
			(at 0.40005 0 90)
			(size 0 0)
			(layers "F.Cu" "F.Mask" "F.Paste")
			(net "PRSNT_CABLE_SWB_B2_ISO_R_N")
		)
	)
	(footprint ""
		(layer "F.Cu")
		(at 370.17833 -338.17814 90)
		(property "Reference" "PR1768"
			(at 0 0 90)
			(layer "F.SilkS")
			(hide yes)
			(effects
				(font
					(size 1.27 1.27)
				)
			)
		)
		(property "Value" ""
			(at 0 0 90)
			(layer "F.Fab")
			(effects
				(font
					(size 1.27 1.27)
				)
			)
		)
		(duplicate_pad_numbers_are_jumpers no)
		(fp_line
			(start 0.7874 -0.4064)
			(end 0.7874 0.4064)
			(stroke
				(width 0.1524)
				(type default)
			)
			(layer "F.SilkS")
		)
		(fp_line
			(start -0.7874 -0.4064)
			(end 0.7874 -0.4064)
			(stroke
				(width 0.1524)
				(type default)
			)
			(layer "F.SilkS")
		)
		(fp_line
			(start 0.7874 0.4064)
			(end -0.7874 0.4064)
			(stroke
				(width 0.1524)
				(type default)
			)
			(layer "F.SilkS")
		)
		(fp_line
			(start -0.7874 0.4064)
			(end -0.7874 -0.4064)
			(stroke
				(width 0.1524)
				(type default)
			)
			(layer "F.SilkS")
		)
		(fp_line
			(start -0.12065 -0.305054)
			(end -0.12065 -0.2794)
			(stroke
				(width 0.1)
				(type default)
			)
			(layer "F.Fab")
		)
		(fp_line
			(start -0.67945 -0.305054)
			(end -0.12065 -0.305054)
			(stroke
				(width 0.1)
				(type default)
			)
			(layer "F.Fab")
		)
		(fp_line
			(start 0.67945 -0.3048)
			(end 0.67945 0.3048)
			(stroke
				(width 0.1)
				(type default)
			)
			(layer "F.Fab")
		)
		(fp_line
			(start 0.12065 -0.3048)
			(end 0.67945 -0.3048)
			(stroke
				(width 0.1)
				(type default)
			)
			(layer "F.Fab")
		)
		(fp_line
			(start 0.12065 -0.2794)
			(end 0.12065 -0.3048)
			(stroke
				(width 0.1)
				(type default)
			)
			(layer "F.Fab")
		)
		(fp_line
			(start -0.12065 -0.2794)
			(end 0.12065 -0.2794)
			(stroke
				(width 0.1)
				(type default)
			)
			(layer "F.Fab")
		)
		(fp_line
			(start 0.120396 0.2794)
			(end -0.12065 0.2794)
			(stroke
				(width 0.1)
				(type default)
			)
			(layer "F.Fab")
		)
		(fp_line
			(start -0.12065 0.2794)
			(end -0.12065 0.3048)
			(stroke
				(width 0.1)
				(type default)
			)
			(layer "F.Fab")
		)
		(fp_line
			(start 0.67945 0.3048)
			(end 0.120396 0.3048)
			(stroke
				(width 0.1)
				(type default)
			)
			(layer "F.Fab")
		)
		(fp_line
			(start 0.120396 0.3048)
			(end 0.120396 0.2794)
			(stroke
				(width 0.1)
				(type default)
			)
			(layer "F.Fab")
		)
		(fp_line
			(start -0.12065 0.3048)
			(end -0.67945 0.3048)
			(stroke
				(width 0.1)
				(type default)
			)
			(layer "F.Fab")
		)
		(fp_line
			(start -0.67945 0.3048)
			(end -0.67945 -0.305054)
			(stroke
				(width 0.1)
				(type default)
			)
			(layer "F.Fab")
		)
		(pad "1" smd circle
			(at -0.40005 0 90)
			(size 0 0)
			(layers "F.Cu" "F.Mask" "F.Paste")
			(net "SW_PVCCIN_CPU0_BOOT4")
		)
		(pad "2" smd circle
			(at 0.40005 0 90)
			(size 0 0)
			(layers "F.Cu" "F.Mask" "F.Paste")
			(net "SW_PVCCIN_CPU0_BOOT4_R")
		)
	)
	(footprint ""
		(layer "F.Cu")
		(at 31.5341 -170.0276)
		(property "Reference" "PC2368"
			(at 0 0 0)
			(layer "F.SilkS")
			(hide yes)
			(effects
				(font
					(size 1.27 1.27)
				)
			)
		)
		(property "Value" ""
			(at 0 0 0)
			(layer "F.Fab")
			(effects
				(font
					(size 1.27 1.27)
				)
			)
		)
		(duplicate_pad_numbers_are_jumpers no)
		(fp_line
			(start -0.7874 -0.4064)
			(end 0.7874 -0.4064)
			(stroke
				(width 0.1524)
				(type default)
			)
			(layer "F.SilkS")
		)
		(fp_line
			(start -0.7874 0.4064)
			(end -0.7874 -0.4064)
			(stroke
				(width 0.1524)
				(type default)
			)
			(layer "F.SilkS")
		)
		(fp_line
			(start 0.7874 -0.4064)
			(end 0.7874 0.4064)
			(stroke
				(width 0.1524)
				(type default)
			)
			(layer "F.SilkS")
		)
		(fp_line
			(start 0.7874 0.4064)
			(end -0.7874 0.4064)
			(stroke
				(width 0.1524)
				(type default)
			)
			(layer "F.SilkS")
		)
		(fp_line
			(start -0.67945 -0.305054)
			(end -0.12065 -0.305054)
			(stroke
				(width 0.1)
				(type default)
			)
			(layer "F.Fab")
		)
		(fp_line
			(start -0.67945 0.3048)
			(end -0.67945 -0.305054)
			(stroke
				(width 0.1)
				(type default)
			)
			(layer "F.Fab")
		)
		(fp_line
			(start -0.12065 -0.305054)
			(end -0.12065 -0.2794)
			(stroke
				(width 0.1)
				(type default)
			)
			(layer "F.Fab")
		)
		(fp_line
			(start -0.12065 -0.2794)
			(end 0.12065 -0.2794)
			(stroke
				(width 0.1)
				(type default)
			)
			(layer "F.Fab")
		)
		(fp_line
			(start -0.12065 0.2794)
			(end -0.12065 0.3048)
			(stroke
				(width 0.1)
				(type default)
			)
			(layer "F.Fab")
		)
		(fp_line
			(start -0.12065 0.3048)
			(end -0.67945 0.3048)
			(stroke
				(width 0.1)
				(type default)
			)
			(layer "F.Fab")
		)
		(fp_line
			(start 0.120396 0.2794)
			(end -0.12065 0.2794)
			(stroke
				(width 0.1)
				(type default)
			)
			(layer "F.Fab")
		)
		(fp_line
			(start 0.120396 0.3048)
			(end 0.120396 0.2794)
			(stroke
				(width 0.1)
				(type default)
			)
			(layer "F.Fab")
		)
		(fp_line
			(start 0.12065 -0.3048)
			(end 0.67945 -0.3048)
			(stroke
				(width 0.1)
				(type default)
			)
			(layer "F.Fab")
		)
		(fp_line
			(start 0.12065 -0.2794)
			(end 0.12065 -0.3048)
			(stroke
				(width 0.1)
				(type default)
			)
			(layer "F.Fab")
		)
		(fp_line
			(start 0.67945 -0.3048)
			(end 0.67945 0.3048)
			(stroke
				(width 0.1)
				(type default)
			)
			(layer "F.Fab")
		)
		(fp_line
			(start 0.67945 0.3048)
			(end 0.120396 0.3048)
			(stroke
				(width 0.1)
				(type default)
			)
			(layer "F.Fab")
		)
		(pad "1" smd circle
			(at -0.40005 0)
			(size 0 0)
			(layers "F.Cu" "F.Mask" "F.Paste")
			(net "PVCCD_HV_CPU1_VCC")
		)
		(pad "2" smd circle
			(at 0.40005 0)
			(size 0 0)
			(layers "F.Cu" "F.Mask" "F.Paste")
			(net "GND")
		)
	)
)
